0.00100 T01
0.00800 T02
0.01000 T03
0.01200 T04
0.01500 T05
0.01574 T06
0.01600 T07
0.01800 T08
0.01968 T09
0.02000 T010
0.02200 T011
0.02400 T012
0.02600 T013
0.02952 T014
0.03000 T015
0.03100 T016
0.03200 T017
0.03400 T018
0.03600 T019
0.03900 T020
0.04000 T021
0.04100 T022
0.04400 T023
0.04500 T024
0.04600 T025
0.04700 T026
0.04900 T027
0.05000 T028
0.05400 T029
0.05900 T030
0.06300 T031
0.06500 T032
0.08400 T033
0.08600 T034
0.08700 T035
0.09600 T036
0.12500 T037
0.12600 T038
0.15000 T039
0.17700 T040
0.22400 T041
